(kicad_pcb
	(version 20260206)
	(generator "pcbnew")
	(generator_version "10.0")
	(general
		(thickness 1.6)
		(legacy_teardrops no)
	)
	(paper "A4")
	(title_block
		(title "03242023_DA0F0TMBIJ0_F0T_Motherboard_J_brd_V01_OCP.brd")
		(comment 1 "Grand Teton / footprints 3312-3316 of 6105")
	)
	(layers
		(0 "F.Cu" signal "TOP")
		(4 "In1.Cu" signal "GND")
		(6 "In2.Cu" signal "IN1")
		(8 "In3.Cu" signal "GND1")
		(10 "In4.Cu" signal "IN2")
		(12 "In5.Cu" signal "GND2")
		(14 "In6.Cu" signal "IN3")
		(16 "In7.Cu" signal "GND3")
		(18 "In8.Cu" signal "VCC")
		(20 "In9.Cu" signal "VCC1")
		(22 "In10.Cu" signal "GND4")
		(24 "In11.Cu" signal "IN4")
		(26 "In12.Cu" signal "GND5")
		(28 "In13.Cu" signal "IN5")
		(30 "In14.Cu" signal "GND6")
		(32 "In15.Cu" signal "IN6")
		(34 "In16.Cu" signal "GND7")
		(2 "B.Cu" signal "BOTTOM")
		(9 "F.Adhes" user "F.Adhesive")
		(11 "B.Adhes" user "B.Adhesive")
		(13 "F.Paste" user "Package Geometry/Pastemask Top")
		(15 "B.Paste" user "Package Geometry/Pastemask Bottom")
		(5 "F.SilkS" user "Ref Des/Silkscreen Top")
		(7 "B.SilkS" user "Ref Des/Silkscreen Bottom")
		(1 "F.Mask" user "Board Geometry/Soldermask Top")
		(3 "B.Mask" user "Board Geometry/Soldermask Bottom")
		(17 "Dwgs.User" user "User.Drawings")
		(19 "Cmts.User" user "User.Comments")
		(21 "Eco1.User" user "User.Eco1")
		(23 "Eco2.User" user "User.Eco2")
		(25 "Edge.Cuts" user "Board Geometry/Outline")
		(27 "Margin" user)
		(31 "F.CrtYd" user "Package Geometry/Place Bound Top")
		(29 "B.CrtYd" user "Package Geometry/Place Bound Bottom")
		(35 "F.Fab" user "Ref Des/Assembly Top")
		(33 "B.Fab" user "Ref Des/Assembly Bottom")
	)
	(footprint ""
		(layer "F.Cu")
		(at 96.997774 -333.716122)
		(property "Reference" "PU31_P1_1"
			(at -2.685796 -6.321298 0)
			(unlocked yes)
			(layer "F.SilkS")
			(effects
				(font
					(size 0.7874 0.5842)
					(thickness 0.1524)
				)
				(justify left)
			)
		)
		(property "Value" ""
			(at 0 0 0)
			(layer "F.Fab")
			(effects
				(font
					(size 1.27 1.27)
				)
			)
		)
		(duplicate_pad_numbers_are_jumpers no)
		(fp_line
			(start -2.500122 -2.999994)
			(end -2.24409 -2.999994)
			(stroke
				(width 0.1524)
				(type default)
			)
			(layer "F.SilkS")
		)
		(fp_line
			(start -2.500122 -2.529078)
			(end -2.500122 -2.999994)
			(stroke
				(width 0.1524)
				(type default)
			)
			(layer "F.SilkS")
		)
		(fp_line
			(start -2.500122 0.6604)
			(end -2.500122 0.229108)
			(stroke
				(width 0.1524)
				(type default)
			)
			(layer "F.SilkS")
		)
		(fp_line
			(start -2.500122 2.999994)
			(end -2.500122 2.339594)
			(stroke
				(width 0.1524)
				(type default)
			)
			(layer "F.SilkS")
		)
		(fp_line
			(start -2.2987 2.999994)
			(end -2.500122 2.999994)
			(stroke
				(width 0.1524)
				(type default)
			)
			(layer "F.SilkS")
		)
		(fp_line
			(start 2.31394 -2.999994)
			(end 2.500122 -2.999994)
			(stroke
				(width 0.1524)
				(type default)
			)
			(layer "F.SilkS")
		)
		(fp_line
			(start 2.500122 -2.999994)
			(end 2.500122 -2.44348)
			(stroke
				(width 0.1524)
				(type default)
			)
			(layer "F.SilkS")
		)
		(fp_line
			(start 2.500122 2.339594)
			(end 2.500122 2.999994)
			(stroke
				(width 0.1524)
				(type default)
			)
			(layer "F.SilkS")
		)
		(fp_line
			(start 2.500122 2.999994)
			(end 2.2987 2.999994)
			(stroke
				(width 0.1524)
				(type default)
			)
			(layer "F.SilkS")
		)
		(fp_poly
			(pts
				(xy -2.162302 -3.588004) (xy -2.670302 -2.572004) (xy -3.178302 -3.588004)
			)
			(stroke
				(width 0)
				(type default)
			)
			(fill yes)
			(layer "F.SilkS")
		)
		(fp_line
			(start -2.500122 -2.999994)
			(end 2.500122 -2.999994)
			(stroke
				(width 0.1)
				(type default)
			)
			(layer "F.Fab")
		)
		(fp_line
			(start -2.500122 2.999994)
			(end -2.500122 -2.999994)
			(stroke
				(width 0.1)
				(type default)
			)
			(layer "F.Fab")
		)
		(fp_line
			(start 2.500122 -2.999994)
			(end 2.500122 2.999994)
			(stroke
				(width 0.1)
				(type default)
			)
			(layer "F.Fab")
		)
		(fp_line
			(start 2.500122 2.999994)
			(end -2.500122 2.999994)
			(stroke
				(width 0.1)
				(type default)
			)
			(layer "F.Fab")
		)
		(fp_poly
			(pts
				(xy -4.218432 -2.783078) (xy -4.218432 -1.767078) (xy -3.202432 -2.275078)
			)
			(stroke
				(width 0)
				(type default)
			)
			(fill yes)
			(layer "F.Fab")
		)
		(pad "1" smd rect
			(at -2.400046 -2.275078 90)
			(size 0.2286 0.6096)
			(layers "F.Cu" "F.Mask" "F.Paste")
			(net "PVCCIN_CPU1_VOS1")
		)
		(pad "2" smd rect
			(at -2.400046 -1.82499 90)
			(size 0.2286 0.6096)
			(layers "F.Cu" "F.Mask" "F.Paste")
			(net "GND")
		)
		(pad "3" smd rect
			(at -2.400046 -1.374902 90)
			(size 0.2286 0.6096)
			(layers "F.Cu" "F.Mask" "F.Paste")
			(net "PVCCIN_CPU1_VDD1")
		)
		(pad "4" smd rect
			(at -2.400046 -0.925068 90)
			(size 0.2286 0.6096)
			(layers "F.Cu" "F.Mask" "F.Paste")
			(net "PVCCIN_CPU1_PVCC")
		)
		(pad "5" smd rect
			(at -2.400046 -0.47498 90)
			(size 0.2286 0.6096)
			(layers "F.Cu" "F.Mask" "F.Paste")
			(net "GND")
		)
		(pad "6" smd rect
			(at -2.400046 -0.024892 90)
			(size 0.2286 0.6096)
			(layers "F.Cu" "F.Mask" "F.Paste")
			(net "Net_8520")
		)
		(pad "7_9-20_24" smd circle
			(at 0 1.150112 90)
			(size 0 0)
			(layers "F.Cu" "F.Mask" "F.Paste")
			(net "GND")
		)
		(pad "10_19" smd rect
			(at 0 2.899918 90)
			(size 0.6096 4.318)
			(layers "F.Cu" "F.Mask" "F.Paste")
			(net "SW_PVCCIN_CPU1_SW1")
		)
		(pad "25_29" smd rect
			(at 1.549908 -1.279906 270)
			(size 2.0574 2.3114)
			(layers "F.Cu" "F.Mask" "F.Paste")
			(net "SW_P12V_PVCCIN_CPU1_FLT")
		)
		(pad "30" smd rect
			(at 2.05994 -2.899918)
			(size 0.2286 0.6096)
			(layers "F.Cu" "F.Mask" "F.Paste")
			(net "SW_P12V_PVCCIN_CPU1_FLT")
		)
		(pad "31" smd rect
			(at 1.610106 -2.899918)
			(size 0.2286 0.6096)
			(layers "F.Cu" "F.Mask" "F.Paste")
			(net "Net_8521")
		)
		(pad "32" smd rect
			(at 1.160018 -2.899918)
			(size 0.2286 0.6096)
			(layers "F.Cu" "F.Mask" "F.Paste")
			(net "SW_PVCCIN_CPU1_BOOTR1")
		)
		(pad "33" smd rect
			(at 0.70993 -2.899918)
			(size 0.2286 0.6096)
			(layers "F.Cu" "F.Mask" "F.Paste")
			(net "SW_PVCCIN_CPU1_BOOT1")
		)
		(pad "34" smd rect
			(at 0.260096 -2.899918)
			(size 0.2286 0.6096)
			(layers "F.Cu" "F.Mask" "F.Paste")
			(net "PVCCIN_CPU1_PWM1")
		)
		(pad "35" smd rect
			(at -0.189992 -2.899918)
			(size 0.2286 0.6096)
			(layers "F.Cu" "F.Mask" "F.Paste")
			(net "PVCCIN_CPU1_VDD1")
		)
		(pad "36" smd rect
			(at -0.64008 -2.899918)
			(size 0.2286 0.6096)
			(layers "F.Cu" "F.Mask" "F.Paste")
			(net "PVCCIN_CPU1_ATSEN")
		)
		(pad "37" smd rect
			(at -1.089914 -2.899918)
			(size 0.2286 0.6096)
			(layers "F.Cu" "F.Mask" "F.Paste")
			(net "PVCCIN_CPU1_LSET1")
		)
		(pad "38" smd rect
			(at -1.540002 -2.899918)
			(size 0.2286 0.6096)
			(layers "F.Cu" "F.Mask" "F.Paste")
			(net "PVCCIN_CPU1_IMON1")
		)
		(pad "39" smd rect
			(at -1.99009 -2.899918)
			(size 0.2286 0.6096)
			(layers "F.Cu" "F.Mask" "F.Paste")
			(net "PVCCIN_CPU1_VREF")
		)
		(pad "40" smd rect
			(at -0.87503 -1.27508)
			(size 1.7526 1.9558)
			(layers "F.Cu" "F.Mask" "F.Paste")
			(net "GND")
		)
		(pad "41" smd rect
			(at -1.525016 0.249936 270)
			(size 0.3048 0.4572)
			(layers "F.Cu" "F.Mask" "F.Paste")
			(net "Net_8519")
		)
		(zone
			(layer "F.Cu")
			(hatch none 0.5)
			(connect_pads
				(clearance 0)
			)
			(min_thickness 0.25)
			(keepout
				(tracks not_allowed)
				(vias allowed)
				(pads allowed)
				(copperpour not_allowed)
				(footprints allowed)
			)
			(placement
				(enabled no)
				(sheetname "")
			)
			(fill
				(thermal_gap 0.5)
				(thermal_bridge_width 0.5)
				(island_removal_mode 0)
			)
			(polygon
				(pts
					(xy 94.497652 -330.716128) (xy 94.497652 -331.465428) (xy 99.497896 -331.465428) (xy 99.497896 -330.716128)
					(xy 99.207574 -330.716128) (xy 99.207574 -331.171804) (xy 94.787974 -331.171804) (xy 94.787974 -330.716128)
				)
			)
		)
		(zone
			(layer "F.Cu")
			(hatch none 0.5)
			(connect_pads
				(clearance 0)
			)
			(min_thickness 0.25)
			(keepout
				(tracks not_allowed)
				(vias allowed)
				(pads allowed)
				(copperpour not_allowed)
				(footprints allowed)
			)
			(placement
				(enabled no)
				(sheetname "")
			)
			(fill
				(thermal_gap 0.5)
				(thermal_bridge_width 0.5)
				(island_removal_mode 0)
			)
			(polygon
				(pts
					(xy 94.953328 -334.040988) (xy 95.195644 -334.040988) (xy 95.195644 -333.962502) (xy 95.96374 -333.962502)
					(xy 95.96374 -333.637128) (xy 96.047052 -333.637128) (xy 96.047052 -332.966822) (xy 94.497652 -332.966822)
					(xy 94.497652 -333.423514) (xy 95.193358 -333.423514) (xy 95.193358 -333.262986) (xy 95.752158 -333.262986)
					(xy 95.752158 -333.669386) (xy 95.193358 -333.669386) (xy 95.193358 -333.448914) (xy 94.497652 -333.448914)
					(xy 94.497652 -333.575914) (xy 94.953328 -333.575914)
				)
			)
		)
	)
	(footprint ""
		(layer "F.Cu")
		(at 438.558432 -27.275536 -90)
		(property "Reference" "PR3842"
			(at 0 0 270)
			(layer "F.SilkS")
			(hide yes)
			(effects
				(font
					(size 1.27 1.27)
				)
			)
		)
		(property "Value" ""
			(at 0 0 270)
			(layer "F.Fab")
			(effects
				(font
					(size 1.27 1.27)
				)
			)
		)
		(duplicate_pad_numbers_are_jumpers no)
		(fp_line
			(start -0.7874 0.4064)
			(end -0.7874 -0.4064)
			(stroke
				(width 0.1524)
				(type default)
			)
			(layer "F.SilkS")
		)
		(fp_line
			(start 0.7874 0.4064)
			(end -0.7874 0.4064)
			(stroke
				(width 0.1524)
				(type default)
			)
			(layer "F.SilkS")
		)
		(fp_line
			(start -0.7874 -0.4064)
			(end 0.7874 -0.4064)
			(stroke
				(width 0.1524)
				(type default)
			)
			(layer "F.SilkS")
		)
		(fp_line
			(start 0.7874 -0.4064)
			(end 0.7874 0.4064)
			(stroke
				(width 0.1524)
				(type default)
			)
			(layer "F.SilkS")
		)
		(fp_line
			(start -0.67945 0.3048)
			(end -0.67945 -0.305054)
			(stroke
				(width 0.1)
				(type default)
			)
			(layer "F.Fab")
		)
		(fp_line
			(start -0.12065 0.3048)
			(end -0.67945 0.3048)
			(stroke
				(width 0.1)
				(type default)
			)
			(layer "F.Fab")
		)
		(fp_line
			(start 0.120396 0.3048)
			(end 0.120396 0.2794)
			(stroke
				(width 0.1)
				(type default)
			)
			(layer "F.Fab")
		)
		(fp_line
			(start 0.67945 0.3048)
			(end 0.120396 0.3048)
			(stroke
				(width 0.1)
				(type default)
			)
			(layer "F.Fab")
		)
		(fp_line
			(start -0.12065 0.2794)
			(end -0.12065 0.3048)
			(stroke
				(width 0.1)
				(type default)
			)
			(layer "F.Fab")
		)
		(fp_line
			(start 0.120396 0.2794)
			(end -0.12065 0.2794)
			(stroke
				(width 0.1)
				(type default)
			)
			(layer "F.Fab")
		)
		(fp_line
			(start -0.12065 -0.2794)
			(end 0.12065 -0.2794)
			(stroke
				(width 0.1)
				(type default)
			)
			(layer "F.Fab")
		)
		(fp_line
			(start 0.12065 -0.2794)
			(end 0.12065 -0.3048)
			(stroke
				(width 0.1)
				(type default)
			)
			(layer "F.Fab")
		)
		(fp_line
			(start 0.12065 -0.3048)
			(end 0.67945 -0.3048)
			(stroke
				(width 0.1)
				(type default)
			)
			(layer "F.Fab")
		)
		(fp_line
			(start 0.67945 -0.3048)
			(end 0.67945 0.3048)
			(stroke
				(width 0.1)
				(type default)
			)
			(layer "F.Fab")
		)
		(fp_line
			(start -0.67945 -0.305054)
			(end -0.12065 -0.305054)
			(stroke
				(width 0.1)
				(type default)
			)
			(layer "F.Fab")
		)
		(fp_line
			(start -0.12065 -0.305054)
			(end -0.12065 -0.2794)
			(stroke
				(width 0.1)
				(type default)
			)
			(layer "F.Fab")
		)
		(pad "1" smd circle
			(at -0.40005 0 270)
			(size 0 0)
			(layers "F.Cu" "F.Mask" "F.Paste")
			(net "P12V_OCP_OV_FB_1")
		)
		(pad "2" smd circle
			(at 0.40005 0 270)
			(size 0 0)
			(layers "F.Cu" "F.Mask" "F.Paste")
			(net "GND")
		)
	)
	(footprint ""
		(layer "F.Cu")
		(at 330.432918 -347.580458 -90)
		(property "Reference" "PC235"
			(at 0 0 270)
			(layer "F.SilkS")
			(hide yes)
			(effects
				(font
					(size 1.27 1.27)
				)
			)
		)
		(property "Value" ""
			(at 0 0 270)
			(layer "F.Fab")
			(effects
				(font
					(size 1.27 1.27)
				)
			)
		)
		(duplicate_pad_numbers_are_jumpers no)
		(fp_line
			(start -0.7874 0.4064)
			(end -0.7874 -0.4064)
			(stroke
				(width 0.1524)
				(type default)
			)
			(layer "F.SilkS")
		)
		(fp_line
			(start 0.7874 0.4064)
			(end -0.7874 0.4064)
			(stroke
				(width 0.1524)
				(type default)
			)
			(layer "F.SilkS")
		)
		(fp_line
			(start -0.7874 -0.4064)
			(end 0.7874 -0.4064)
			(stroke
				(width 0.1524)
				(type default)
			)
			(layer "F.SilkS")
		)
		(fp_line
			(start 0.7874 -0.4064)
			(end 0.7874 0.4064)
			(stroke
				(width 0.1524)
				(type default)
			)
			(layer "F.SilkS")
		)
		(fp_line
			(start -0.67945 0.3048)
			(end -0.67945 -0.305054)
			(stroke
				(width 0.1)
				(type default)
			)
			(layer "F.Fab")
		)
		(fp_line
			(start -0.12065 0.3048)
			(end -0.67945 0.3048)
			(stroke
				(width 0.1)
				(type default)
			)
			(layer "F.Fab")
		)
		(fp_line
			(start 0.120396 0.3048)
			(end 0.120396 0.2794)
			(stroke
				(width 0.1)
				(type default)
			)
			(layer "F.Fab")
		)
		(fp_line
			(start 0.67945 0.3048)
			(end 0.120396 0.3048)
			(stroke
				(width 0.1)
				(type default)
			)
			(layer "F.Fab")
		)
		(fp_line
			(start -0.12065 0.2794)
			(end -0.12065 0.3048)
			(stroke
				(width 0.1)
				(type default)
			)
			(layer "F.Fab")
		)
		(fp_line
			(start 0.120396 0.2794)
			(end -0.12065 0.2794)
			(stroke
				(width 0.1)
				(type default)
			)
			(layer "F.Fab")
		)
		(fp_line
			(start -0.12065 -0.2794)
			(end 0.12065 -0.2794)
			(stroke
				(width 0.1)
				(type default)
			)
			(layer "F.Fab")
		)
		(fp_line
			(start 0.12065 -0.2794)
			(end 0.12065 -0.3048)
			(stroke
				(width 0.1)
				(type default)
			)
			(layer "F.Fab")
		)
		(fp_line
			(start 0.12065 -0.3048)
			(end 0.67945 -0.3048)
			(stroke
				(width 0.1)
				(type default)
			)
			(layer "F.Fab")
		)
		(fp_line
			(start 0.67945 -0.3048)
			(end 0.67945 0.3048)
			(stroke
				(width 0.1)
				(type default)
			)
			(layer "F.Fab")
		)
		(fp_line
			(start -0.67945 -0.305054)
			(end -0.12065 -0.305054)
			(stroke
				(width 0.1)
				(type default)
			)
			(layer "F.Fab")
		)
		(fp_line
			(start -0.12065 -0.305054)
			(end -0.12065 -0.2794)
			(stroke
				(width 0.1)
				(type default)
			)
			(layer "F.Fab")
		)
		(pad "1" smd circle
			(at -0.40005 0 270)
			(size 0 0)
			(layers "F.Cu" "F.Mask" "F.Paste")
			(net "SW_PVCCIN_CPU0_BOOT7_R")
		)
		(pad "2" smd circle
			(at 0.40005 0 270)
			(size 0 0)
			(layers "F.Cu" "F.Mask" "F.Paste")
			(net "SW_PVCCIN_CPU0_BOOTR7")
		)
	)
	(footprint ""
		(layer "F.Cu")
		(at 408.554682 -162.185858 180)
		(property "Reference" "PL35"
			(at -0.979678 4.10464 0)
			(unlocked yes)
			(layer "F.SilkS")
			(effects
				(font
					(size 0.7874 0.5842)
					(thickness 0.1524)
				)
				(justify left)
			)
		)
		(property "Value" ""
			(at 0 0 180)
			(layer "F.Fab")
			(effects
				(font
					(size 1.27 1.27)
				)
			)
		)
		(duplicate_pad_numbers_are_jumpers no)
		(fp_line
			(start 3.24993 3.24993)
			(end -3.24993 3.24993)
			(stroke
				(width 0.1524)
				(type default)
			)
			(layer "F.SilkS")
		)
		(fp_line
			(start 3.24993 2.2352)
			(end 3.24993 3.24993)
			(stroke
				(width 0.1524)
				(type default)
			)
			(layer "F.SilkS")
		)
		(fp_line
			(start 3.24993 -3.24993)
			(end 3.24993 -2.2352)
			(stroke
				(width 0.1524)
				(type default)
			)
			(layer "F.SilkS")
		)
		(fp_line
			(start -3.24993 3.24993)
			(end -3.24993 2.2352)
			(stroke
				(width 0.1524)
				(type default)
			)
			(layer "F.SilkS")
		)
		(fp_line
			(start -3.24993 -2.2352)
			(end -3.24993 -3.24993)
			(stroke
				(width 0.1524)
				(type default)
			)
			(layer "F.SilkS")
		)
		(fp_line
			(start -3.24993 -3.24993)
			(end 3.24993 -3.24993)
			(stroke
				(width 0.1524)
				(type default)
			)
			(layer "F.SilkS")
		)
		(fp_line
			(start 3.24993 3.24993)
			(end -3.24993 3.24993)
			(stroke
				(width 0.1)
				(type default)
			)
			(layer "F.Fab")
		)
		(fp_line
			(start 3.24993 -3.24993)
			(end 3.24993 3.24993)
			(stroke
				(width 0.1)
				(type default)
			)
			(layer "F.Fab")
		)
		(fp_line
			(start -3.24993 3.24993)
			(end -3.24993 -3.24993)
			(stroke
				(width 0.1)
				(type default)
			)
			(layer "F.Fab")
		)
		(fp_line
			(start -3.24993 -3.24993)
			(end 3.24993 -3.24993)
			(stroke
				(width 0.1)
				(type default)
			)
			(layer "F.Fab")
		)
		(pad "1" smd rect
			(at -2.29997 0 180)
			(size 2.0066 4.2164)
			(layers "F.Cu" "F.Mask" "F.Paste")
			(net "SW_PVCCD_HV_CPU0_SW1")
		)
		(pad "2" smd rect
			(at 2.29997 0 180)
			(size 2.0066 4.2164)
			(layers "F.Cu" "F.Mask" "F.Paste")
			(net "PVCCD_HV_CPU0")
		)
	)
	(footprint ""
		(layer "F.Cu")
		(at 397.24965 -408.517344 -90)
		(property "Reference" "C886"
			(at 0 0 270)
			(layer "F.SilkS")
			(hide yes)
			(effects
				(font
					(size 1.27 1.27)
				)
			)
		)
		(property "Value" ""
			(at 0 0 270)
			(layer "F.Fab")
			(effects
				(font
					(size 1.27 1.27)
				)
			)
		)
		(duplicate_pad_numbers_are_jumpers no)
		(fp_line
			(start -0.299974 0.150114)
			(end -0.299974 -0.150114)
			(stroke
				(width 0.1)
				(type default)
			)
			(layer "F.Fab")
		)
		(fp_line
			(start 0.299974 0.150114)
			(end -0.299974 0.150114)
			(stroke
				(width 0.1)
				(type default)
			)
			(layer "F.Fab")
		)
		(fp_line
			(start -0.299974 -0.150114)
			(end 0.299974 -0.150114)
			(stroke
				(width 0.1)
				(type default)
			)
			(layer "F.Fab")
		)
		(fp_line
			(start 0.299974 -0.150114)
			(end 0.299974 0.150114)
			(stroke
				(width 0.1)
				(type default)
			)
			(layer "F.Fab")
		)
		(pad "1" smd rect
			(at -0.2667 0 270)
			(size 0.3048 0.381)
			(layers "F.Cu" "F.Mask" "F.Paste")
			(net "P5E_CPU0_PE3_TX_C_DN<7>")
		)
		(pad "2" smd rect
			(at 0.2667 0 270)
			(size 0.3048 0.381)
			(layers "F.Cu" "F.Mask" "F.Paste")
			(net "P5E_CPU0_PE3_TX_DN<7>")
		)
	)
)
